(kicad_pcb
	(version 20260206)
	(generator "pcbnew")
	(generator_version "10.0")
	(general
		(thickness 1.6)
		(legacy_teardrops no)
	)
	(paper "A4")
	(title_block
		(title "pdpb — Lightning_PDPB_BRD.brd")
		(comment 1 "Lightning (Wiwynn / Facebook NVMe JBOF) / footprints 84-91 of 1140")
	)
	(layers
		(0 "F.Cu" signal "TOP")
		(4 "In1.Cu" signal "L2GND")
		(6 "In2.Cu" signal "L3")
		(8 "In3.Cu" signal "L4VCC")
		(10 "In4.Cu" signal "L5VCC")
		(12 "In5.Cu" signal "L6")
		(14 "In6.Cu" signal "L7GND")
		(2 "B.Cu" signal "BOTTOM")
		(9 "F.Adhes" user "F.Adhesive")
		(11 "B.Adhes" user "B.Adhesive")
		(13 "F.Paste" user "Package Geometry/Pastemask Top")
		(15 "B.Paste" user "Package Geometry/Pastemask Bottom")
		(5 "F.SilkS" user "Ref Des/Silkscreen Top")
		(7 "B.SilkS" user "Ref Des/Silkscreen Bottom")
		(1 "F.Mask" user "Board Geometry/Soldermask Top")
		(3 "B.Mask" user "Board Geometry/Soldermask Bottom")
		(17 "Dwgs.User" user "User.Drawings")
		(19 "Cmts.User" user "User.Comments")
		(21 "Eco1.User" user "User.Eco1")
		(23 "Eco2.User" user "User.Eco2")
		(25 "Edge.Cuts" user "Board Geometry/Outline")
		(27 "Margin" user)
		(31 "F.CrtYd" user "Package Geometry/Place Bound Top")
		(29 "B.CrtYd" user "Package Geometry/Place Bound Bottom")
		(35 "F.Fab" user "Ref Des/Assembly Top")
		(33 "B.Fab" user "Ref Des/Assembly Bottom")
	)
	(footprint ""
		(layer "F.Cu")
		(at 44.677076 -344.118692)
		(property "Reference" "C9524"
			(at 0 0 0)
			(layer "F.SilkS")
			(hide yes)
			(effects
				(font
					(size 1.27 1.27)
				)
			)
		)
		(property "Value" "SCD1U16V2KX-3GP"
			(at 1.1811 -2.7051 0)
			(unlocked yes)
			(layer "F.Fab")
			(hide yes)
			(effects
				(font
					(size 1.016 1.016)
					(thickness 0.1524)
				)
			)
		)
		(property "Device Type" "C402H22"
			(at 1.1811 -4.2291 0)
			(unlocked yes)
			(layer "F.Fab")
			(hide yes)
			(effects
				(font
					(size 1.016 1.016)
					(thickness 0.1524)
				)
			)
		)
		(duplicate_pad_numbers_are_jumpers no)
		(fp_rect
			(start -0.4318 0.9525)
			(end 0.4318 -0.9525)
			(stroke
				(width 0)
				(type default)
			)
			(fill no)
			(layer "F.CrtYd")
		)
		(fp_rect
			(start -0.4318 0.9525)
			(end 0.4318 -0.9525)
			(stroke
				(width 0)
				(type default)
			)
			(fill no)
			(layer "F.Fab")
		)
		(pad "1" smd custom
			(at 0 -0.4445)
			(size 0.1524 0.1524)
			(layers "F.Cu" "F.Mask" "F.Paste")
			(net "P3V3")
			(options
				(clearance outline)
				(anchor circle)
			)
			(primitives
				(gr_poly
					(pts
						(arc
							(start 0.3048 -0.2032)
							(mid 0.275042 -0.275042)
							(end 0.2032 -0.3048)
						)
						(arc
							(start -0.2032 -0.3048)
							(mid -0.275042 -0.275042)
							(end -0.3048 -0.2032)
						)
						(arc
							(start -0.3048 0.2032)
							(mid -0.275042 0.275042)
							(end -0.2032 0.3048)
						)
						(arc
							(start 0.2032 0.3048)
							(mid 0.275042 0.275042)
							(end 0.3048 0.2032)
						)
					)
					(width 0)
					(fill yes)
				)
			)
		)
		(pad "2" smd custom
			(at 0 0.4445)
			(size 0.1524 0.1524)
			(layers "F.Cu" "F.Mask" "F.Paste")
			(net "GND")
			(options
				(clearance outline)
				(anchor circle)
			)
			(primitives
				(gr_poly
					(pts
						(arc
							(start 0.3048 -0.2032)
							(mid 0.275042 -0.275042)
							(end 0.2032 -0.3048)
						)
						(arc
							(start -0.2032 -0.3048)
							(mid -0.275042 -0.275042)
							(end -0.3048 -0.2032)
						)
						(arc
							(start -0.3048 0.2032)
							(mid -0.275042 0.275042)
							(end -0.2032 0.3048)
						)
						(arc
							(start 0.2032 0.3048)
							(mid 0.275042 0.275042)
							(end 0.3048 0.2032)
						)
					)
					(width 0)
					(fill yes)
				)
			)
		)
	)
	(footprint ""
		(layer "F.Cu")
		(at 106.045 -310.261 180)
		(property "Reference" "C9365"
			(at 0 0 180)
			(layer "F.SilkS")
			(hide yes)
			(effects
				(font
					(size 1.27 1.27)
				)
			)
		)
		(property "Value" "SC1KP50V2KX-1GP"
			(at 1.1811 -2.7051 180)
			(unlocked yes)
			(layer "F.Fab")
			(hide yes)
			(effects
				(font
					(size 1.016 1.016)
					(thickness 0.1524)
				)
			)
		)
		(property "Device Type" "C402H22"
			(at 1.1811 -4.2291 180)
			(unlocked yes)
			(layer "F.Fab")
			(hide yes)
			(effects
				(font
					(size 1.016 1.016)
					(thickness 0.1524)
				)
			)
		)
		(duplicate_pad_numbers_are_jumpers no)
		(fp_rect
			(start -0.4318 0.9525)
			(end 0.4318 -0.9525)
			(stroke
				(width 0)
				(type default)
			)
			(fill no)
			(layer "F.CrtYd")
		)
		(fp_rect
			(start -0.4318 0.9525)
			(end 0.4318 -0.9525)
			(stroke
				(width 0)
				(type default)
			)
			(fill no)
			(layer "F.Fab")
		)
		(pad "1" smd custom
			(at 0 -0.4445 180)
			(size 0.1524 0.1524)
			(layers "F.Cu" "F.Mask" "F.Paste")
			(net "SSD1_CLK0_OE_R_N")
			(options
				(clearance outline)
				(anchor circle)
			)
			(primitives
				(gr_poly
					(pts
						(arc
							(start 0.3048 -0.2032)
							(mid 0.275042 -0.275042)
							(end 0.2032 -0.3048)
						)
						(arc
							(start -0.2032 -0.3048)
							(mid -0.275042 -0.275042)
							(end -0.3048 -0.2032)
						)
						(arc
							(start -0.3048 0.2032)
							(mid -0.275042 0.275042)
							(end -0.2032 0.3048)
						)
						(arc
							(start 0.2032 0.3048)
							(mid 0.275042 0.275042)
							(end 0.3048 0.2032)
						)
					)
					(width 0)
					(fill yes)
				)
			)
		)
		(pad "2" smd custom
			(at 0 0.4445 180)
			(size 0.1524 0.1524)
			(layers "F.Cu" "F.Mask" "F.Paste")
			(net "GND")
			(options
				(clearance outline)
				(anchor circle)
			)
			(primitives
				(gr_poly
					(pts
						(arc
							(start 0.3048 -0.2032)
							(mid 0.275042 -0.275042)
							(end 0.2032 -0.3048)
						)
						(arc
							(start -0.2032 -0.3048)
							(mid -0.275042 -0.275042)
							(end -0.3048 -0.2032)
						)
						(arc
							(start -0.3048 0.2032)
							(mid -0.275042 0.275042)
							(end -0.2032 0.3048)
						)
						(arc
							(start 0.2032 0.3048)
							(mid 0.275042 0.275042)
							(end 0.3048 0.2032)
						)
					)
					(width 0)
					(fill yes)
				)
			)
		)
	)
	(footprint ""
		(layer "F.Cu")
		(at 38.989 -142.24 180)
		(property "Reference" "U205"
			(at 0 0 180)
			(layer "F.SilkS")
			(hide yes)
			(effects
				(font
					(size 1.27 1.27)
				)
			)
		)
		(property "Value" "SN74LVC1G08DCKR-GP"
			(at -2.3368 -8.6868 180)
			(unlocked yes)
			(layer "F.Fab")
			(hide yes)
			(effects
				(font
					(size 1.016 1.016)
					(thickness 0.1524)
				)
			)
		)
		(property "Device Type" "SC70-5H44"
			(at -2.3114 -10.414 180)
			(unlocked yes)
			(layer "F.Fab")
			(hide yes)
			(effects
				(font
					(size 1.016 1.016)
					(thickness 0.1524)
				)
			)
		)
		(duplicate_pad_numbers_are_jumpers no)
		(fp_line
			(start 1.3843 -1.8034)
			(end 1.3843 -1.1176)
			(stroke
				(width 0.3302)
				(type default)
			)
			(layer "F.SilkS")
		)
		(fp_line
			(start 1.27 1.7018)
			(end -1.27 1.7018)
			(stroke
				(width 0.1524)
				(type default)
			)
			(layer "F.SilkS")
		)
		(fp_line
			(start 1.27 -1.7018)
			(end 1.27 1.7018)
			(stroke
				(width 0.1524)
				(type default)
			)
			(layer "F.SilkS")
		)
		(fp_line
			(start 0.6604 -1.8034)
			(end 1.3843 -1.8034)
			(stroke
				(width 0.3302)
				(type default)
			)
			(layer "F.SilkS")
		)
		(fp_line
			(start -1.27 1.7018)
			(end -1.27 -1.7018)
			(stroke
				(width 0.1524)
				(type default)
			)
			(layer "F.SilkS")
		)
		(fp_line
			(start -1.27 -1.7018)
			(end 1.27 -1.7018)
			(stroke
				(width 0.1524)
				(type default)
			)
			(layer "F.SilkS")
		)
		(fp_rect
			(start -1.524 1.9558)
			(end 1.524 -1.9558)
			(stroke
				(width 0)
				(type default)
			)
			(fill no)
			(layer "F.CrtYd")
		)
		(fp_poly
			(pts
				(xy -1.524 -1.9558) (xy 1.524 -1.9558) (xy 1.524 1.9558) (xy -1.524 1.9558)
			)
			(stroke
				(width 0)
				(type default)
			)
			(fill no)
			(layer "F.Fab")
		)
		(pad "1" smd rect
			(at 0.65024 -0.8255 180)
			(size 0.4064 1.2192)
			(layers "F.Cu" "F.Mask" "F.Paste")
			(net "SSD8_CLK0_OE_MOS_N")
		)
		(pad "2" smd rect
			(at 0 -0.8255 180)
			(size 0.4064 1.2192)
			(layers "F.Cu" "F.Mask" "F.Paste")
			(net "ATTN_LED_DR8_N")
		)
		(pad "3" smd rect
			(at -0.65024 -0.8255 180)
			(size 0.4064 1.2192)
			(layers "F.Cu" "F.Mask" "F.Paste")
			(net "GND")
		)
		(pad "4" smd rect
			(at -0.65024 0.8255 180)
			(size 0.4064 1.2192)
			(layers "F.Cu" "F.Mask" "F.Paste")
			(net "ATTN_LED_DR8_AND")
		)
		(pad "5" smd rect
			(at 0.65024 0.8255 180)
			(size 0.4064 1.2192)
			(layers "F.Cu" "F.Mask" "F.Paste")
			(net "P3V3")
		)
	)
	(footprint ""
		(layer "F.Cu")
		(at 200.365106 -491.110778 180)
		(property "Reference" "R566"
			(at 0 0 180)
			(layer "F.SilkS")
			(hide yes)
			(effects
				(font
					(size 1.27 1.27)
				)
			)
		)
		(property "Value" "300KR2F-GP"
			(at 0.064008 -3.993896 180)
			(unlocked yes)
			(layer "F.Fab")
			(hide yes)
			(effects
				(font
					(size 1.016 1.016)
					(thickness 0.1524)
				)
			)
		)
		(property "Device Type" "R402H16"
			(at 0.064008 -5.517896 180)
			(unlocked yes)
			(layer "F.Fab")
			(hide yes)
			(effects
				(font
					(size 1.016 1.016)
					(thickness 0.1524)
				)
			)
		)
		(duplicate_pad_numbers_are_jumpers no)
		(fp_line
			(start 0.508 -0.9398)
			(end -0.508 -0.9398)
			(stroke
				(width 0.1524)
				(type default)
			)
			(layer "F.SilkS")
		)
		(fp_line
			(start -0.508 -0.9398)
			(end -0.508 0.9398)
			(stroke
				(width 0.1524)
				(type default)
			)
			(layer "F.SilkS")
		)
		(fp_rect
			(start -0.508 0.9398)
			(end 0.508 -0.9398)
			(stroke
				(width 0)
				(type default)
			)
			(fill no)
			(layer "F.CrtYd")
		)
		(fp_rect
			(start -0.508 0.9398)
			(end 0.508 -0.9398)
			(stroke
				(width 0)
				(type default)
			)
			(fill no)
			(layer "F.Fab")
		)
		(pad "1" smd custom
			(at 0 -0.4445 180)
			(size 0.1397 0.1397)
			(layers "F.Cu" "F.Mask" "F.Paste")
			(net "SW_SSD0_N")
			(options
				(clearance outline)
				(anchor circle)
			)
			(primitives
				(gr_poly
					(pts
						(arc
							(start -0.1778 -0.2794)
							(mid -0.249642 -0.249642)
							(end -0.2794 -0.1778)
						)
						(arc
							(start -0.2794 0.1778)
							(mid -0.249642 0.249642)
							(end -0.1778 0.2794)
						)
						(arc
							(start 0.1778 0.2794)
							(mid 0.249642 0.249642)
							(end 0.2794 0.1778)
						)
						(arc
							(start 0.2794 -0.1778)
							(mid 0.249642 -0.249642)
							(end 0.1778 -0.2794)
						)
					)
					(width 0)
					(fill yes)
				)
			)
		)
		(pad "2" smd custom
			(at 0 0.4445 180)
			(size 0.1397 0.1397)
			(layers "F.Cu" "F.Mask" "F.Paste")
			(net "P12V")
			(options
				(clearance outline)
				(anchor circle)
			)
			(primitives
				(gr_poly
					(pts
						(arc
							(start -0.1778 -0.2794)
							(mid -0.249642 -0.249642)
							(end -0.2794 -0.1778)
						)
						(arc
							(start -0.2794 0.1778)
							(mid -0.249642 0.249642)
							(end -0.1778 0.2794)
						)
						(arc
							(start 0.1778 0.2794)
							(mid 0.249642 0.249642)
							(end 0.2794 0.1778)
						)
						(arc
							(start 0.2794 -0.1778)
							(mid 0.249642 -0.249642)
							(end 0.1778 -0.2794)
						)
					)
					(width 0)
					(fill yes)
				)
			)
		)
	)
	(footprint ""
		(layer "F.Cu")
		(at 35.0266 -91.3384 180)
		(property "Reference" "PC1195"
			(at 0 0 180)
			(layer "F.SilkS")
			(hide yes)
			(effects
				(font
					(size 1.27 1.27)
				)
			)
		)
		(property "Value" "SC22U25V6KX-GP-U"
			(at -2.860802 -5.279644 180)
			(unlocked yes)
			(layer "F.Fab")
			(hide yes)
			(effects
				(font
					(size 1.016 1.016)
					(thickness 0.1524)
				)
			)
		)
		(property "Device Type" "C1206-TO0D3H75"
			(at -2.860802 -6.803644 180)
			(unlocked yes)
			(layer "F.Fab")
			(hide yes)
			(effects
				(font
					(size 1.016 1.016)
					(thickness 0.1524)
				)
			)
		)
		(duplicate_pad_numbers_are_jumpers no)
		(fp_line
			(start 1.3081 2.3749)
			(end -1.3081 2.3749)
			(stroke
				(width 0.1524)
				(type default)
			)
			(layer "F.SilkS")
		)
		(fp_line
			(start 1.3081 -2.3749)
			(end 1.3081 2.3749)
			(stroke
				(width 0.1524)
				(type default)
			)
			(layer "F.SilkS")
		)
		(fp_line
			(start -1.3081 2.3749)
			(end -1.3081 -2.3749)
			(stroke
				(width 0.1524)
				(type default)
			)
			(layer "F.SilkS")
		)
		(fp_line
			(start -1.3081 -2.3749)
			(end 1.3081 -2.3749)
			(stroke
				(width 0.1524)
				(type default)
			)
			(layer "F.SilkS")
		)
		(fp_rect
			(start -0.8001 1.6002)
			(end 0.8001 -1.6002)
			(stroke
				(width 0)
				(type default)
			)
			(fill no)
			(layer "F.CrtYd")
		)
		(fp_poly
			(pts
				(xy -1.5621 2.4511) (xy -1.5621 1.6002) (xy 0.8001 1.6002) (xy 0.8001 -1.6002) (xy -0.8001 -1.6002)
				(xy -0.8001 1.5875) (xy -1.5621 1.5875) (xy -1.5621 -2.4511) (xy 1.5621 -2.4511) (xy 1.5621 2.4511)
			)
			(stroke
				(width 0)
				(type default)
			)
			(fill no)
			(layer "F.CrtYd")
		)
		(fp_rect
			(start -1.5621 2.4511)
			(end 1.5621 -2.4511)
			(stroke
				(width 0)
				(type default)
			)
			(fill no)
			(layer "F.Fab")
		)
		(pad "1" smd rect
			(at 0 -1.392936 180)
			(size 2.1082 1.4478)
			(layers "F.Cu" "F.Mask" "F.Paste")
			(net "P12V_SSD9")
		)
		(pad "2" smd rect
			(at 0 1.392936 180)
			(size 2.1082 1.4478)
			(layers "F.Cu" "F.Mask" "F.Paste")
			(net "GND")
		)
	)
	(footprint ""
		(layer "F.Cu")
		(at 8.499856 -261.500112)
		(property "Reference" "H6"
			(at 0 0 0)
			(layer "F.SilkS")
			(hide yes)
			(effects
				(font
					(size 1.27 1.27)
				)
			)
		)
		(property "Value" "HOLE315R140-GP"
			(at 0 -7.5692 0)
			(unlocked yes)
			(layer "F.Fab")
			(hide yes)
			(effects
				(font
					(size 1.016 1.016)
					(thickness 0.1524)
				)
			)
		)
		(property "Device Type" "HOLE315R140"
			(at 0 -9.0932 0)
			(unlocked yes)
			(layer "F.Fab")
			(hide yes)
			(effects
				(font
					(size 1.016 1.016)
					(thickness 0.1524)
				)
			)
		)
		(duplicate_pad_numbers_are_jumpers no)
		(fp_poly
			(pts
				(arc
					(start 4.3053 0)
					(mid -4.3053 0)
					(end 4.3053 0)
				)
			)
			(stroke
				(width 0)
				(type default)
			)
			(fill no)
			(layer "F.CrtYd")
		)
		(fp_poly
			(pts
				(arc
					(start 4.3053 0)
					(mid -4.3053 0)
					(end 4.3053 0)
				)
			)
			(stroke
				(width 0)
				(type default)
			)
			(fill no)
			(layer "F.Fab")
		)
		(pad "1" thru_hole circle
			(at 0.00127 0.00127)
			(size 8.001 8.001)
			(drill 3.556)
			(layers "*.Cu" "*.Mask")
			(remove_unused_layers no)
			(net "GND")
			(clearance -1.7145)
			(thermal_gap 0.3048)
			(padstack
				(mode front_inner_back)
				(layer "Inner"
					(shape circle)
					(size 3.9624 3.9624)
					(clearance 0.3048)
				)
				(layer "B.Cu"
					(shape circle)
					(size 8.001 8.001)
					(clearance -1.7145)
				)
			)
		)
	)
	(footprint ""
		(layer "F.Cu")
		(at 24.003 -258.191 -90)
		(property "Reference" "R9478"
			(at 0 0 270)
			(layer "F.SilkS")
			(hide yes)
			(effects
				(font
					(size 1.27 1.27)
				)
			)
		)
		(property "Value" "100R2J-2-GP"
			(at 0.064008 -3.993896 270)
			(unlocked yes)
			(layer "F.Fab")
			(hide yes)
			(effects
				(font
					(size 1.016 1.016)
					(thickness 0.1524)
				)
			)
		)
		(property "Device Type" "R402H14"
			(at 0.064008 -5.517896 270)
			(unlocked yes)
			(layer "F.Fab")
			(hide yes)
			(effects
				(font
					(size 1.016 1.016)
					(thickness 0.1524)
				)
			)
		)
		(duplicate_pad_numbers_are_jumpers no)
		(fp_line
			(start -0.508 -0.9398)
			(end -0.508 0.9398)
			(stroke
				(width 0.1524)
				(type default)
			)
			(layer "F.SilkS")
		)
		(fp_line
			(start 0.508 -0.9398)
			(end -0.508 -0.9398)
			(stroke
				(width 0.1524)
				(type default)
			)
			(layer "F.SilkS")
		)
		(fp_rect
			(start -0.508 0.9398)
			(end 0.508 -0.9398)
			(stroke
				(width 0)
				(type default)
			)
			(fill no)
			(layer "F.CrtYd")
		)
		(fp_rect
			(start -0.508 0.9398)
			(end 0.508 -0.9398)
			(stroke
				(width 0)
				(type default)
			)
			(fill no)
			(layer "F.Fab")
		)
		(pad "1" smd custom
			(at 0 -0.4445 270)
			(size 0.1397 0.1397)
			(layers "F.Cu" "F.Mask" "F.Paste")
			(net "P3V3")
			(options
				(clearance outline)
				(anchor circle)
			)
			(primitives
				(gr_poly
					(pts
						(arc
							(start -0.1778 -0.2794)
							(mid -0.249642 -0.249642)
							(end -0.2794 -0.1778)
						)
						(arc
							(start -0.2794 0.1778)
							(mid -0.249642 0.249642)
							(end -0.1778 0.2794)
						)
						(arc
							(start 0.1778 0.2794)
							(mid 0.249642 0.249642)
							(end 0.2794 0.1778)
						)
						(arc
							(start 0.2794 -0.1778)
							(mid 0.249642 -0.249642)
							(end 0.1778 -0.2794)
						)
					)
					(width 0)
					(fill yes)
				)
			)
		)
		(pad "2" smd custom
			(at 0 0.4445 270)
			(size 0.1397 0.1397)
			(layers "F.Cu" "F.Mask" "F.Paste")
			(net "DRV_ACT_12")
			(options
				(clearance outline)
				(anchor circle)
			)
			(primitives
				(gr_poly
					(pts
						(arc
							(start -0.1778 -0.2794)
							(mid -0.249642 -0.249642)
							(end -0.2794 -0.1778)
						)
						(arc
							(start -0.2794 0.1778)
							(mid -0.249642 0.249642)
							(end -0.1778 0.2794)
						)
						(arc
							(start 0.1778 0.2794)
							(mid 0.249642 0.249642)
							(end 0.2794 0.1778)
						)
						(arc
							(start 0.2794 -0.1778)
							(mid 0.249642 -0.249642)
							(end 0.1778 -0.2794)
						)
					)
					(width 0)
					(fill yes)
				)
			)
		)
	)
	(footprint ""
		(layer "F.Cu")
		(at 22.987 -393.827)
		(property "Reference" "R557"
			(at 0 0 0)
			(layer "F.SilkS")
			(hide yes)
			(effects
				(font
					(size 1.27 1.27)
				)
			)
		)
		(property "Value" "200KR2F-L-GP"
			(at 0.064008 -3.993896 0)
			(unlocked yes)
			(layer "F.Fab")
			(hide yes)
			(effects
				(font
					(size 1.016 1.016)
					(thickness 0.1524)
				)
			)
		)
		(property "Device Type" "R402H16"
			(at 0.064008 -5.517896 0)
			(unlocked yes)
			(layer "F.Fab")
			(hide yes)
			(effects
				(font
					(size 1.016 1.016)
					(thickness 0.1524)
				)
			)
		)
		(duplicate_pad_numbers_are_jumpers no)
		(fp_line
			(start -0.508 -0.9398)
			(end -0.508 0.9398)
			(stroke
				(width 0.1524)
				(type default)
			)
			(layer "F.SilkS")
		)
		(fp_line
			(start 0.508 -0.9398)
			(end -0.508 -0.9398)
			(stroke
				(width 0.1524)
				(type default)
			)
			(layer "F.SilkS")
		)
		(fp_rect
			(start -0.508 0.9398)
			(end 0.508 -0.9398)
			(stroke
				(width 0)
				(type default)
			)
			(fill no)
			(layer "F.CrtYd")
		)
		(fp_rect
			(start -0.508 0.9398)
			(end 0.508 -0.9398)
			(stroke
				(width 0)
				(type default)
			)
			(fill no)
			(layer "F.Fab")
		)
		(pad "1" smd custom
			(at 0 -0.4445)
			(size 0.1397 0.1397)
			(layers "F.Cu" "F.Mask" "F.Paste")
			(net "SW_SSD6_R")
			(options
				(clearance outline)
				(anchor circle)
			)
			(primitives
				(gr_poly
					(pts
						(arc
							(start -0.1778 -0.2794)
							(mid -0.249642 -0.249642)
							(end -0.2794 -0.1778)
						)
						(arc
							(start -0.2794 0.1778)
							(mid -0.249642 0.249642)
							(end -0.1778 0.2794)
						)
						(arc
							(start 0.1778 0.2794)
							(mid 0.249642 0.249642)
							(end 0.2794 0.1778)
						)
						(arc
							(start 0.2794 -0.1778)
							(mid 0.249642 -0.249642)
							(end 0.1778 -0.2794)
						)
					)
					(width 0)
					(fill yes)
				)
			)
		)
		(pad "2" smd custom
			(at 0 0.4445)
			(size 0.1397 0.1397)
			(layers "F.Cu" "F.Mask" "F.Paste")
			(net "SW_SSD6_N")
			(options
				(clearance outline)
				(anchor circle)
			)
			(primitives
				(gr_poly
					(pts
						(arc
							(start -0.1778 -0.2794)
							(mid -0.249642 -0.249642)
							(end -0.2794 -0.1778)
						)
						(arc
							(start -0.2794 0.1778)
							(mid -0.249642 0.249642)
							(end -0.1778 0.2794)
						)
						(arc
							(start 0.1778 0.2794)
							(mid 0.249642 0.249642)
							(end 0.2794 0.1778)
						)
						(arc
							(start 0.2794 -0.1778)
							(mid 0.249642 -0.249642)
							(end 0.1778 -0.2794)
						)
					)
					(width 0)
					(fill yes)
				)
			)
		)
	)
)
